# BASEBOARD_FAB2 (Tioga Pass) — schematic netlist excerpt (pin names and nets, part order shuffled) for the footprints in the layout excerpt that follows; sources: Cadence DE-HDL packaged netlist, KiCad conversion of Wiwynn_Tioga_Pass_MB.brd

C1F14  CAP  0.22UF 16V 10% X7R  pkg 0402  page 181 : A = P3E_CPU1_PE3_MP_C_TXP<2> ; B = P3E_CPU1_PE3_MP_TXP<2>

U25W10  GTL2014  IC  pkg SM  page 254
  DIR  = PU_GTL2014_3_DIR
  B0  = XDP_PREQ_N
  B1  = XDP_CPU_PWR_DEBUG_N
  VREF  = PD_GTL2014_3_VREF
  B2  = XDP_TDI_R
  B3  = XDP_TMS_R
  GND(0)  = GND
  GND(1)  = GND
  A3  = JTAG_BMC_BUF_TMS
  A2  = JTAG_BMC_BUF_TDI
  GND(2)  = GND
  A1  = BMC_PWR_DEBUG_BUF_N
  A0  = BMC_PREQ_BUF_N
  VCC  = P3V3_STBY

(kicad_pcb
	(version 20260206)
	(generator "pcbnew")
	(generator_version "10.0")
	(general
		(thickness 1.6)
		(legacy_teardrops no)
	)
	(paper "A4")
	(title_block
		(title "Wiwynn_Tioga_Pass_MB.brd")
		(comment 1 "Tioga Pass / footprints 78-79 of 4770")
	)
	(layers
		(0 "F.Cu" signal "TOP")
		(4 "In1.Cu" signal "L2GND")
		(6 "In2.Cu" signal "L3")
		(8 "In3.Cu" signal "L4GND")
		(10 "In4.Cu" signal "L5")
		(12 "In5.Cu" signal "L6GND")
		(14 "In6.Cu" signal "L7VCC")
		(16 "In7.Cu" signal "L8VCC")
		(18 "In8.Cu" signal "L9GND")
		(20 "In9.Cu" signal "L10")
		(22 "In10.Cu" signal "L11GND")
		(24 "In11.Cu" signal "L12")
		(26 "In12.Cu" signal "L13GND")
		(2 "B.Cu" signal "BOTTOM")
		(9 "F.Adhes" user "F.Adhesive")
		(11 "B.Adhes" user "B.Adhesive")
		(13 "F.Paste" user "Package Geometry/Pastemask Top")
		(15 "B.Paste" user "Package Geometry/Pastemask Bottom")
		(5 "F.SilkS" user "Ref Des/Silkscreen Top")
		(7 "B.SilkS" user "Ref Des/Silkscreen Bottom")
		(1 "F.Mask" user "Board Geometry/Soldermask Top")
		(3 "B.Mask" user "Board Geometry/Soldermask Bottom")
		(17 "Dwgs.User" user "User.Drawings")
		(19 "Cmts.User" user "User.Comments")
		(21 "Eco1.User" user "User.Eco1")
		(23 "Eco2.User" user "User.Eco2")
		(25 "Edge.Cuts" user "Board Geometry/Outline")
		(27 "Margin" user)
		(31 "F.CrtYd" user "Package Geometry/Place Bound Top")
		(29 "B.CrtYd" user "Package Geometry/Place Bound Bottom")
		(35 "F.Fab" user "Ref Des/Assembly Top")
		(33 "B.Fab" user "Ref Des/Assembly Bottom")
	)
	(footprint ""
		(layer "F.Cu")
		(at 13.8938 -27.686 90)
		(property "Reference" "C1F14"
			(at 0 0 90)
			(layer "F.SilkS")
			(hide yes)
			(effects
				(font
					(size 1.27 1.27)
				)
			)
		)
		(property "Value" ""
			(at 0 0 90)
			(layer "F.Fab")
			(effects
				(font
					(size 1.27 1.27)
				)
			)
		)
		(duplicate_pad_numbers_are_jumpers no)
		(fp_rect
			(start -0.3048 -0.1016)
			(end 0.3048 0.9906)
			(stroke
				(width 0)
				(type default)
			)
			(fill no)
			(layer "F.CrtYd")
		)
		(fp_line
			(start 0.3048 -0.1016)
			(end -0.3048 -0.1016)
			(stroke
				(width 0.1)
				(type default)
			)
			(layer "F.Fab")
		)
		(fp_line
			(start -0.3048 -0.1016)
			(end -0.3048 0.9906)
			(stroke
				(width 0.1)
				(type default)
			)
			(layer "F.Fab")
		)
		(fp_line
			(start 0.3048 0.9906)
			(end 0.3048 -0.1016)
			(stroke
				(width 0.1)
				(type default)
			)
			(layer "F.Fab")
		)
		(fp_line
			(start -0.3048 0.9906)
			(end 0.3048 0.9906)
			(stroke
				(width 0.1)
				(type default)
			)
			(layer "F.Fab")
		)
		(pad "1" smd rect
			(at 0 0 90)
			(size 0.508 0.508)
			(layers "F.Cu" "F.Mask" "F.Paste")
			(net "P3E_CPU1_PE3_MP_C_TXP<2>")
		)
		(pad "2" smd rect
			(at 0 0.889 90)
			(size 0.508 0.508)
			(layers "F.Cu" "F.Mask" "F.Paste")
			(net "P3E_CPU1_PE3_MP_TXP<2>")
		)
		(zone
			(layer "F.Cu")
			(hatch none 0.5)
			(connect_pads
				(clearance 0)
			)
			(min_thickness 0.25)
			(keepout
				(tracks allowed)
				(vias not_allowed)
				(pads allowed)
				(copperpour not_allowed)
				(footprints allowed)
			)
			(placement
				(enabled no)
				(sheetname "")
			)
			(fill
				(thermal_gap 0.5)
				(thermal_bridge_width 0.5)
				(island_removal_mode 0)
			)
			(polygon
				(pts
					(xy 14.1478 -27.432) (xy 14.5288 -27.432) (xy 14.5288 -27.94) (xy 14.1478 -27.94)
				)
			)
		)
		(zone
			(layer "F.Cu")
			(hatch none 0.5)
			(connect_pads
				(clearance 0)
			)
			(min_thickness 0.25)
			(keepout
				(tracks not_allowed)
				(vias allowed)
				(pads allowed)
				(copperpour not_allowed)
				(footprints allowed)
			)
			(placement
				(enabled no)
				(sheetname "")
			)
			(fill
				(thermal_gap 0.5)
				(thermal_bridge_width 0.5)
				(island_removal_mode 0)
			)
			(polygon
				(pts
					(xy 14.1478 -27.432) (xy 14.5288 -27.432) (xy 14.5288 -27.94) (xy 14.1478 -27.94)
				)
			)
		)
	)
	(footprint ""
		(layer "F.Cu")
		(at 450.461634 -141.30909 180)
		(property "Reference" "U25W10"
			(at 2.159 -1.57988 180)
			(unlocked yes)
			(layer "F.SilkS")
			(effects
				(font
					(size 0.4064 0.254)
					(thickness 0.1524)
				)
				(justify left)
			)
		)
		(property "Value" ""
			(at 0 0 180)
			(layer "F.Fab")
			(effects
				(font
					(size 1.27 1.27)
				)
			)
		)
		(duplicate_pad_numbers_are_jumpers no)
		(fp_line
			(start 4.4323 4.52628)
			(end 1.5367 4.52628)
			(stroke
				(width 0.1524)
				(type default)
			)
			(layer "F.SilkS")
		)
		(fp_line
			(start 4.4323 -0.64008)
			(end 4.4323 4.52628)
			(stroke
				(width 0.1524)
				(type default)
			)
			(layer "F.SilkS")
		)
		(fp_line
			(start 3.302 0.49022)
			(end 3.302 -0.64008)
			(stroke
				(width 0.1524)
				(type default)
			)
			(layer "F.SilkS")
		)
		(fp_line
			(start 2.667 0.49022)
			(end 3.302 0.49022)
			(stroke
				(width 0.1524)
				(type default)
			)
			(layer "F.SilkS")
		)
		(fp_line
			(start 2.667 -0.64008)
			(end 2.667 0.49022)
			(stroke
				(width 0.1524)
				(type default)
			)
			(layer "F.SilkS")
		)
		(fp_line
			(start 1.5367 4.52628)
			(end 1.5367 -0.64008)
			(stroke
				(width 0.1524)
				(type default)
			)
			(layer "F.SilkS")
		)
		(fp_line
			(start 1.5367 -0.64008)
			(end 4.4323 -0.64008)
			(stroke
				(width 0.1524)
				(type default)
			)
			(layer "F.SilkS")
		)
		(fp_circle
			(center -1.612138 -0.684784)
			(end -1.739138 -0.684784)
			(stroke
				(width 0.254)
				(type default)
			)
			(fill no)
			(layer "F.SilkS")
		)
		(fp_poly
			(pts
				(xy 0.7366 4.54152) (xy 0.7366 -0.64008) (xy 4.7244 -0.64008) (xy 5.2324 -0.64008) (xy 5.2324 4.54152)
				(xy 4.7244 4.54152)
			)
			(stroke
				(width 0)
				(type default)
			)
			(fill no)
			(layer "F.CrtYd")
		)
		(fp_line
			(start 5.2324 4.54152)
			(end 0.7366 4.54152)
			(stroke
				(width 0.1)
				(type default)
			)
			(layer "F.Fab")
		)
		(fp_line
			(start 5.2324 -0.64008)
			(end 5.2324 4.54152)
			(stroke
				(width 0.1)
				(type default)
			)
			(layer "F.Fab")
		)
		(fp_line
			(start 3.302 0.49022)
			(end 3.302 -0.64008)
			(stroke
				(width 0.1)
				(type default)
			)
			(layer "F.Fab")
		)
		(fp_line
			(start 2.667 0.49022)
			(end 3.302 0.49022)
			(stroke
				(width 0.1)
				(type default)
			)
			(layer "F.Fab")
		)
		(fp_line
			(start 2.667 -0.64008)
			(end 2.667 0.49022)
			(stroke
				(width 0.1)
				(type default)
			)
			(layer "F.Fab")
		)
		(fp_line
			(start 0.7366 4.54152)
			(end 0.7366 -0.64008)
			(stroke
				(width 0.1)
				(type default)
			)
			(layer "F.Fab")
		)
		(fp_line
			(start 0.7366 -0.64008)
			(end 5.2324 -0.64008)
			(stroke
				(width 0.1)
				(type default)
			)
			(layer "F.Fab")
		)
		(fp_circle
			(center -1.612138 -0.684784)
			(end -1.739138 -0.684784)
			(stroke
				(width 0.254)
				(type default)
			)
			(fill no)
			(layer "F.Fab")
		)
		(pad "1" smd rect
			(at 0 0 180)
			(size 2.159 0.381)
			(layers "F.Cu" "F.Mask" "F.Paste")
			(net "PU_GTL2014_3_DIR")
		)
		(pad "2" smd rect
			(at 0 0.65024 180)
			(size 2.159 0.381)
			(layers "F.Cu" "F.Mask" "F.Paste")
			(net "XDP_PREQ_N")
		)
		(pad "3" smd rect
			(at 0 1.30048 180)
			(size 2.159 0.381)
			(layers "F.Cu" "F.Mask" "F.Paste")
			(net "XDP_CPU_PWR_DEBUG_N")
		)
		(pad "4" smd rect
			(at 0 1.95072 180)
			(size 2.159 0.381)
			(layers "F.Cu" "F.Mask" "F.Paste")
			(net "PD_GTL2014_3_VREF")
		)
		(pad "5" smd rect
			(at 0 2.60096 180)
			(size 2.159 0.381)
			(layers "F.Cu" "F.Mask" "F.Paste")
			(net "XDP_TDI_R")
		)
		(pad "6" smd rect
			(at 0 3.2512 180)
			(size 2.159 0.381)
			(layers "F.Cu" "F.Mask" "F.Paste")
			(net "XDP_TMS_R")
		)
		(pad "7" smd rect
			(at 0 3.90144 180)
			(size 2.159 0.381)
			(layers "F.Cu" "F.Mask" "F.Paste")
			(net "GND")
		)
		(pad "8" smd rect
			(at 5.969 3.90144 180)
			(size 2.159 0.381)
			(layers "F.Cu" "F.Mask" "F.Paste")
			(net "GND")
		)
		(pad "9" smd rect
			(at 5.969 3.2512 180)
			(size 2.159 0.381)
			(layers "F.Cu" "F.Mask" "F.Paste")
			(net "JTAG_BMC_BUF_TMS")
		)
		(pad "10" smd rect
			(at 5.969 2.60096 180)
			(size 2.159 0.381)
			(layers "F.Cu" "F.Mask" "F.Paste")
			(net "JTAG_BMC_BUF_TDI")
		)
		(pad "11" smd rect
			(at 5.969 1.95072 180)
			(size 2.159 0.381)
			(layers "F.Cu" "F.Mask" "F.Paste")
			(net "GND")
		)
		(pad "12" smd rect
			(at 5.969 1.30048 180)
			(size 2.159 0.381)
			(layers "F.Cu" "F.Mask" "F.Paste")
			(net "BMC_PWR_DEBUG_BUF_N")
		)
		(pad "13" smd rect
			(at 5.969 0.65024 180)
			(size 2.159 0.381)
			(layers "F.Cu" "F.Mask" "F.Paste")
			(net "BMC_PREQ_BUF_N")
		)
		(pad "14" smd rect
			(at 5.969 0 180)
			(size 2.159 0.381)
			(layers "F.Cu" "F.Mask" "F.Paste")
			(net "P3V3_STBY")
		)
	)
)
